(kicad_pcb
	(version 20260206)
	(generator "pcbnew")
	(generator_version "10.0")
	(general
		(thickness 1.21888)
		(legacy_teardrops no)
	)
	(paper "A4")
	(title_block
		(title "timecard-v7 — TimeCard-DC-V7_EXP.PcbDoc")
		(comment 1 "Time Appliance Project (Time Card) / footprints 103-112 of 160")
	)
	(layers
		(0 "F.Cu" signal "TOP")
		(4 "In1.Cu" signal "SGND")
		(6 "In2.Cu" signal "IN1")
		(8 "In3.Cu" signal "IN2")
		(10 "In4.Cu" signal "SGND1")
		(2 "B.Cu" signal "BOTTOM")
		(9 "F.Adhes" user "F.Adhesive")
		(11 "B.Adhes" user "B.Adhesive")
		(13 "F.Paste" user "Top Paste")
		(15 "B.Paste" user "Bottom Paste")
		(5 "F.SilkS" user "Top Overlay")
		(7 "B.SilkS" user "Bottom Overlay")
		(1 "F.Mask" user "Top Solder")
		(3 "B.Mask" user "Bottom Solder")
		(17 "Dwgs.User" user "User.Drawings")
		(19 "Cmts.User" user "User.Comments")
		(21 "Eco1.User" user "User.Eco1")
		(23 "Eco2.User" user "User.Eco2")
		(25 "Edge.Cuts" user)
		(27 "Margin" user)
		(31 "F.CrtYd" user "Top Courtyard")
		(29 "B.CrtYd" user "Bottom Courtyard")
		(35 "F.Fab" user "Top Component Center")
		(33 "B.Fab" user "Bottom Component Center")
	)
	(footprint "IS32FL3207:IS32FL3207"
		(layer "F.Cu")
		(at 89.3761 87.1162)
		(property "Reference" "U6"
			(at -2.271395 -3.723079 0)
			(unlocked yes)
			(layer "F.SilkS")
			(effects
				(font
					(size 0.762 0.762)
					(thickness 0.2286)
				)
			)
		)
		(property "Value" "IS32FL3207"
			(at 4.20136 4.689602 0)
			(unlocked yes)
			(layer "F.SilkS")
			(hide yes)
			(effects
				(font
					(size 1.524 1.524)
					(thickness 0.254)
				)
			)
		)
		(sheetname "USER_IO_STATUS")
		(sheetfile "USER_IO_STATUS.kicad_sch")
		(duplicate_pad_numbers_are_jumpers no)
		(fp_line
			(start -2.65 -2.65)
			(end -2.05 -2.65)
			(stroke
				(width 0.2)
				(type solid)
			)
			(layer "F.SilkS")
		)
		(fp_line
			(start -2.65 -2.05)
			(end -2.65 -2.65)
			(stroke
				(width 0.2)
				(type solid)
			)
			(layer "F.SilkS")
		)
		(fp_line
			(start -2.65 2.65)
			(end -2.65 2.05)
			(stroke
				(width 0.2)
				(type solid)
			)
			(layer "F.SilkS")
		)
		(fp_line
			(start -2.65 2.65)
			(end -2.05 2.65)
			(stroke
				(width 0.2)
				(type solid)
			)
			(layer "F.SilkS")
		)
		(fp_line
			(start 2.05 -2.65)
			(end 2.65 -2.65)
			(stroke
				(width 0.2)
				(type solid)
			)
			(layer "F.SilkS")
		)
		(fp_line
			(start 2.05 2.65)
			(end 2.65 2.65)
			(stroke
				(width 0.2)
				(type solid)
			)
			(layer "F.SilkS")
		)
		(fp_line
			(start 2.65 -2.05)
			(end 2.65 -2.65)
			(stroke
				(width 0.2)
				(type solid)
			)
			(layer "F.SilkS")
		)
		(fp_line
			(start 2.65 2.65)
			(end 2.65 2.05)
			(stroke
				(width 0.2)
				(type solid)
			)
			(layer "F.SilkS")
		)
		(fp_circle
			(center -3.3 -2.5)
			(end -3.3 -2.625)
			(stroke
				(width 0.25)
				(type solid)
			)
			(fill no)
			(layer "F.SilkS")
		)
		(pad "1" smd rect
			(at -2.325 -1.5 90)
			(size 0.26 0.9)
			(layers "F.Cu" "F.Mask" "F.Paste")
			(net "NetC39_2")
		)
		(pad "2" smd rect
			(at -2.325 -1 90)
			(size 0.26 0.9)
			(layers "F.Cu" "F.Mask" "F.Paste")
			(net "+3.3V")
		)
		(pad "3" smd rect
			(at -2.325 -0.5 90)
			(size 0.26 0.9)
			(layers "F.Cu" "F.Mask" "F.Paste")
			(net "+3.3V")
		)
		(pad "4" smd rect
			(at -2.325 0 90)
			(size 0.26 0.9)
			(layers "F.Cu" "F.Mask" "F.Paste")
			(net "GND")
		)
		(pad "5" smd rect
			(at -2.325 0.5 90)
			(size 0.26 0.9)
			(layers "F.Cu" "F.Mask" "F.Paste")
			(net "NetR41_2")
		)
		(pad "6" smd rect
			(at -2.325 1 90)
			(size 0.26 0.9)
			(layers "F.Cu" "F.Mask" "F.Paste")
			(net "SDA")
		)
		(pad "7" smd rect
			(at -2.325 1.5 90)
			(size 0.26 0.9)
			(layers "F.Cu" "F.Mask" "F.Paste")
			(net "SCL")
		)
		(pad "8" smd rect
			(at -1.5 2.325)
			(size 0.26 0.9)
			(layers "F.Cu" "F.Mask" "F.Paste")
			(net "NetD13_4")
		)
		(pad "9" smd rect
			(at -1 2.325)
			(size 0.26 0.9)
			(layers "F.Cu" "F.Mask" "F.Paste")
			(net "NetD13_3")
		)
		(pad "10" smd rect
			(at -0.5 2.325)
			(size 0.26 0.9)
			(layers "F.Cu" "F.Mask" "F.Paste")
			(net "NetD13_2")
		)
		(pad "11" smd rect
			(at 0 2.325)
			(size 0.26 0.9)
			(layers "F.Cu" "F.Mask" "F.Paste")
			(net "GND")
		)
		(pad "12" smd rect
			(at 0.5 2.325)
			(size 0.26 0.9)
			(layers "F.Cu" "F.Mask" "F.Paste")
			(net "NetD14_4")
		)
		(pad "13" smd rect
			(at 1 2.325)
			(size 0.26 0.9)
			(layers "F.Cu" "F.Mask" "F.Paste")
			(net "NetD14_3")
		)
		(pad "14" smd rect
			(at 1.5 2.325)
			(size 0.26 0.9)
			(layers "F.Cu" "F.Mask" "F.Paste")
			(net "NetD14_2")
		)
		(pad "15" smd rect
			(at 2.325 1.5 90)
			(size 0.26 0.9)
			(layers "F.Cu" "F.Mask" "F.Paste")
			(net "NetD15_4")
		)
		(pad "16" smd rect
			(at 2.325 1 90)
			(size 0.26 0.9)
			(layers "F.Cu" "F.Mask" "F.Paste")
			(net "NetD15_3")
		)
		(pad "17" smd rect
			(at 2.325 0.5 90)
			(size 0.26 0.9)
			(layers "F.Cu" "F.Mask" "F.Paste")
			(net "NetD15_2")
		)
		(pad "18" smd rect
			(at 2.325 0 90)
			(size 0.26 0.9)
			(layers "F.Cu" "F.Mask" "F.Paste")
			(net "GND")
		)
		(pad "19" smd rect
			(at 2.325 -0.5 90)
			(size 0.26 0.9)
			(layers "F.Cu" "F.Mask" "F.Paste")
			(net "NetD16_4")
		)
		(pad "20" smd rect
			(at 2.325 -1 90)
			(size 0.26 0.9)
			(layers "F.Cu" "F.Mask" "F.Paste")
			(net "NetD16_3")
		)
		(pad "21" smd rect
			(at 2.325 -1.5 90)
			(size 0.26 0.9)
			(layers "F.Cu" "F.Mask" "F.Paste")
			(net "NetD16_2")
		)
		(pad "22" smd rect
			(at 1.5 -2.325)
			(size 0.26 0.9)
			(layers "F.Cu" "F.Mask" "F.Paste")
			(net "NetD17_4")
		)
		(pad "23" smd rect
			(at 1 -2.325)
			(size 0.26 0.9)
			(layers "F.Cu" "F.Mask" "F.Paste")
			(net "NetD17_3")
		)
		(pad "24" smd rect
			(at 0.5 -2.325)
			(size 0.26 0.9)
			(layers "F.Cu" "F.Mask" "F.Paste")
			(net "NetD17_2")
		)
		(pad "25" smd rect
			(at 0 -2.325)
			(size 0.26 0.9)
			(layers "F.Cu" "F.Mask" "F.Paste")
			(net "GND")
		)
		(pad "26" smd rect
			(at -0.5 -2.325)
			(size 0.26 0.9)
			(layers "F.Cu" "F.Mask" "F.Paste")
			(net "NetD18_4")
		)
		(pad "27" smd rect
			(at -1 -2.325)
			(size 0.26 0.9)
			(layers "F.Cu" "F.Mask" "F.Paste")
			(net "NetD18_3")
		)
		(pad "28" smd rect
			(at -1.5 -2.325)
			(size 0.26 0.9)
			(layers "F.Cu" "F.Mask" "F.Paste")
			(net "NetD18_2")
		)
		(pad "29" smd rect
			(at 0 0)
			(size 3.25 3.25)
			(layers "F.Cu" "F.Mask" "F.Paste")
			(net "GND")
		)
	)
	(footprint "Vault:CAPC1608X87X45ML20T05"
		(layer "F.Cu")
		(at 225.6261 115.8162 -90)
		(property "Reference" "C2"
			(at -2.25 -0.343345 90)
			(unlocked yes)
			(layer "F.SilkS")
			(effects
				(font
					(size 0.762 0.762)
					(thickness 0.2286)
				)
				(justify left bottom)
			)
		)
		(property "Value" "0.1uF"
			(at 2.31879 1.4493 0)
			(unlocked yes)
			(layer "F.SilkS")
			(hide yes)
			(effects
				(font
					(size 1.524 1.524)
					(thickness 0.254)
				)
				(justify left bottom)
			)
		)
		(sheetname "POWER")
		(sheetfile "POWER.kicad_sch")
		(duplicate_pad_numbers_are_jumpers no)
		(pad "1" smd rect
			(at -0.7 0)
			(size 1.1 1.05)
			(layers "F.Cu" "F.Mask" "F.Paste")
			(net "GND")
		)
		(pad "2" smd rect
			(at 0.7 0)
			(size 1.1 1.05)
			(layers "F.Cu" "F.Mask" "F.Paste")
			(net "+12V")
		)
	)
	(footprint "SamacSys:SOP50P310X90-8N"
		(layer "F.Cu")
		(at 82.3761 122.3662 180)
		(property "Reference" "U11"
			(at 0.153605 2.026921 180)
			(unlocked yes)
			(layer "F.SilkS")
			(effects
				(font
					(size 0.762 0.762)
					(thickness 0.2286)
				)
			)
		)
		(property "Value" "NC7WV125K8X"
			(at 6.233115 2.911602 180)
			(unlocked yes)
			(layer "F.SilkS")
			(hide yes)
			(effects
				(font
					(size 1.524 1.524)
					(thickness 0.254)
				)
			)
		)
		(sheetname "USER_IO")
		(sheetfile "USER_IO.kicad_sch")
		(duplicate_pad_numbers_are_jumpers no)
		(fp_line
			(start 0.8 1)
			(end -0.8 1)
			(stroke
				(width 0.2)
				(type solid)
			)
			(layer "F.SilkS")
		)
		(fp_line
			(start 0.8 -1)
			(end 0.8 1)
			(stroke
				(width 0.2)
				(type solid)
			)
			(layer "F.SilkS")
		)
		(fp_line
			(start 0.8 -1)
			(end -0.8 -1)
			(stroke
				(width 0.2)
				(type solid)
			)
			(layer "F.SilkS")
		)
		(fp_line
			(start -0.8 -1)
			(end -0.8 1)
			(stroke
				(width 0.2)
				(type solid)
			)
			(layer "F.SilkS")
		)
		(fp_line
			(start -1.15 -1.25)
			(end -2 -1.25)
			(stroke
				(width 0.2)
				(type solid)
			)
			(layer "F.SilkS")
		)
		(pad "1" smd rect
			(at -1.575 -0.75 180)
			(size 0.85 0.3)
			(layers "F.Cu" "F.Mask" "F.Paste")
			(net "ANT3_IO_OUT")
		)
		(pad "2" smd rect
			(at -1.575 -0.25 180)
			(size 0.85 0.3)
			(layers "F.Cu" "F.Mask" "F.Paste")
			(net "ANT3_OUT")
		)
		(pad "3" smd rect
			(at -1.575 0.25 180)
			(size 0.85 0.3)
			(layers "F.Cu" "F.Mask" "F.Paste")
			(net "ANT3_IN")
		)
		(pad "4" smd rect
			(at -1.575 0.75 180)
			(size 0.85 0.3)
			(layers "F.Cu" "F.Mask" "F.Paste")
			(net "GND")
		)
		(pad "5" smd rect
			(at 1.575 0.75 180)
			(size 0.85 0.3)
			(layers "F.Cu" "F.Mask" "F.Paste")
			(net "NetR28_1")
		)
		(pad "6" smd rect
			(at 1.575 0.25 180)
			(size 0.85 0.3)
			(layers "F.Cu" "F.Mask" "F.Paste")
			(net "NetR28_1")
		)
		(pad "7" smd rect
			(at 1.575 -0.25 180)
			(size 0.85 0.3)
			(layers "F.Cu" "F.Mask" "F.Paste")
			(net "ANT3_IO_IN")
		)
		(pad "8" smd rect
			(at 1.575 -0.75 180)
			(size 0.85 0.3)
			(layers "F.Cu" "F.Mask" "F.Paste")
			(net "+3.3V")
		)
	)
	(footprint "Vault:RESC1608X55X30NL15T15"
		(layer "F.Cu")
		(at 75.1261 55.6162 90)
		(property "Reference" "R39"
			(at -5.7714 0.026921 90)
			(unlocked yes)
			(layer "F.SilkS")
			(effects
				(font
					(size 0.762 0.762)
					(thickness 0.2286)
				)
			)
		)
		(property "Value" "200 OHM"
			(at -2.962402 4.81166 0)
			(unlocked yes)
			(layer "F.SilkS")
			(hide yes)
			(effects
				(font
					(size 1.524 1.524)
					(thickness 0.254)
				)
			)
		)
		(sheetname "USER_IO_STATUS")
		(sheetfile "USER_IO_STATUS.kicad_sch")
		(duplicate_pad_numbers_are_jumpers no)
		(pad "1" smd rect
			(at -0.675 0 180)
			(size 0.95 0.8)
			(layers "F.Cu" "F.Mask" "F.Paste")
			(net "LED4")
		)
		(pad "2" smd rect
			(at 0.675 0 180)
			(size 0.95 0.8)
			(layers "F.Cu" "F.Mask" "F.Paste")
			(net "NetD11_1")
		)
	)
	(footprint "Resistors:RESC1608X50N"
		(layer "F.Cu")
		(at 208.7885 107.6662 180)
		(property "Reference" "R8"
			(at 1.5 0.393345 180)
			(unlocked yes)
			(layer "F.SilkS")
			(effects
				(font
					(size 0.762 0.762)
					(thickness 0.2286)
				)
				(justify left bottom)
			)
		)
		(property "Value" "ERJ-3EKF2201V"
			(at -7.3553 -5.15659 0)
			(unlocked yes)
			(layer "F.SilkS")
			(hide yes)
			(effects
				(font
					(size 1.524 1.524)
					(thickness 0.254)
				)
				(justify left bottom)
			)
		)
		(sheetname "POWER")
		(sheetfile "POWER.kicad_sch")
		(duplicate_pad_numbers_are_jumpers no)
		(fp_line
			(start 0 -0.5)
			(end 0 0.5)
			(stroke
				(width 0.1524)
				(type solid)
			)
			(layer "F.SilkS")
		)
		(pad "1" smd rect
			(at -0.69 0 270)
			(size 1 0.72)
			(layers "F.Cu" "F.Mask" "F.Paste")
			(net "GND")
		)
		(pad "2" smd rect
			(at 0.69 0 270)
			(size 1 0.72)
			(layers "F.Cu" "F.Mask" "F.Paste")
			(net "NetC20_1")
		)
	)
	(footprint "Resistors:RESC2012X50N"
		(layer "F.Cu")
		(at 224.9261 142.2162 -90)
		(property "Reference" "R21"
			(at -1.25 -1.406655 270)
			(unlocked yes)
			(layer "F.SilkS")
			(effects
				(font
					(size 0.762 0.762)
					(thickness 0.2286)
				)
				(justify left bottom)
			)
		)
		(property "Value" "CRCW080533R0FKEA"
			(at -3.08581 -11.2251 0)
			(unlocked yes)
			(layer "F.SilkS")
			(hide yes)
			(effects
				(font
					(size 1.524 1.524)
					(thickness 0.254)
				)
				(justify left bottom)
			)
		)
		(sheetname "PCIe_JTAG")
		(sheetfile "PCIe_JTAG.kicad_sch")
		(duplicate_pad_numbers_are_jumpers no)
		(fp_line
			(start 0 0.762)
			(end 0 -0.762)
			(stroke
				(width 0.1524)
				(type solid)
			)
			(layer "F.SilkS")
		)
		(pad "1" smd rect
			(at -1 0)
			(size 1.45 0.95)
			(layers "F.Cu" "F.Mask" "F.Paste")
			(net "FPGA_TDI")
		)
		(pad "2" smd rect
			(at 1 0)
			(size 1.45 0.95)
			(layers "F.Cu" "F.Mask" "F.Paste")
			(net "NetR21_2")
		)
	)
	(footprint "Vault:FP-5TS1-IPC_C"
		(layer "F.Cu")
		(at 180.1261 87.0786 -90)
		(property "Reference" "U7"
			(at -2.723069 0.771405 0)
			(unlocked yes)
			(layer "F.SilkS")
			(effects
				(font
					(size 0.762 0.762)
					(thickness 0.2286)
				)
			)
		)
		(property "Value" "AT24MAC402-STUM-T"
			(at 10.752795 3.216402 270)
			(unlocked yes)
			(layer "F.SilkS")
			(hide yes)
			(effects
				(font
					(size 1.524 1.524)
					(thickness 0.254)
				)
			)
		)
		(sheetname "GPS_IMU_SENSORS")
		(sheetfile "GPS_IMU_SENSORS.kicad_sch")
		(duplicate_pad_numbers_are_jumpers no)
		(fp_line
			(start 0.17207 1.45)
			(end -0.17207 1.45)
			(stroke
				(width 0.2)
				(type solid)
			)
			(layer "F.SilkS")
		)
		(fp_line
			(start 0.8 0.30894)
			(end 0.8 -0.30893)
			(stroke
				(width 0.2)
				(type solid)
			)
			(layer "F.SilkS")
		)
		(fp_line
			(start 0.17207 -1.45)
			(end -0.17207 -1.45)
			(stroke
				(width 0.2)
				(type solid)
			)
			(layer "F.SilkS")
		)
		(fp_circle
			(center -2.21035 -0.95)
			(end -2.33535 -0.95)
			(stroke
				(width 0.25)
				(type solid)
			)
			(fill no)
			(layer "F.SilkS")
		)
		(fp_line
			(start -1.68536 1.55)
			(end -1.68536 -1.55)
			(stroke
				(width 0.2)
				(type solid)
			)
			(layer "F.CrtYd")
		)
		(fp_line
			(start 1.68536 1.55)
			(end -1.68536 1.55)
			(stroke
				(width 0.2)
				(type solid)
			)
			(layer "F.CrtYd")
		)
		(fp_line
			(start 1.68536 1.55)
			(end 1.68536 -1.55)
			(stroke
				(width 0.2)
				(type solid)
			)
			(layer "F.CrtYd")
		)
		(fp_line
			(start 1.68536 -1.55)
			(end -1.68536 -1.55)
			(stroke
				(width 0.2)
				(type solid)
			)
			(layer "F.CrtYd")
		)
		(fp_line
			(start -1.68536 1.55)
			(end -1.68536 -1.55)
			(stroke
				(width 0.2)
				(type solid)
			)
			(layer "F.Fab")
		)
		(fp_line
			(start 1.68536 1.55)
			(end -1.68536 1.55)
			(stroke
				(width 0.2)
				(type solid)
			)
			(layer "F.Fab")
		)
		(fp_line
			(start 1.68536 1.55)
			(end 1.68536 -1.55)
			(stroke
				(width 0.2)
				(type solid)
			)
			(layer "F.Fab")
		)
		(fp_line
			(start 0 0.5)
			(end 0 -0.5)
			(stroke
				(width 0.1)
				(type solid)
			)
			(layer "F.Fab")
		)
		(fp_line
			(start 0.5 0)
			(end -0.5 0)
			(stroke
				(width 0.1)
				(type solid)
			)
			(layer "F.Fab")
		)
		(fp_line
			(start 1.68536 -1.55)
			(end -1.68536 -1.55)
			(stroke
				(width 0.2)
				(type solid)
			)
			(layer "F.Fab")
		)
		(fp_text user "${REFERENCE}"
			(at 0 0.28425 270)
			(unlocked yes)
			(layer "F.Fab")
			(effects
				(font
					(face "Arial")
					(size 0.63 0.63)
					(thickness 0.1)
				)
				(justify left bottom)
			)
		)
		(pad "1" smd rect
			(at -1.06621 -0.95 270)
			(size 1.03828 0.53213)
			(layers "F.Cu" "F.Mask" "F.Paste")
			(net "SCL")
			(solder_mask_margin 0)
			(solder_paste_margin 0)
		)
		(pad "2" smd roundrect
			(at -1.06621 0 270)
			(size 1.03828 0.53213)
			(layers "F.Cu" "F.Mask" "F.Paste")
			(roundrect_rratio 0.5)
			(net "GND")
			(solder_mask_margin 0)
			(solder_paste_margin 0)
		)
		(pad "3" smd roundrect
			(at -1.06621 0.95 270)
			(size 1.03828 0.53213)
			(layers "F.Cu" "F.Mask" "F.Paste")
			(roundrect_rratio 0.5)
			(net "SDA")
			(solder_mask_margin 0)
			(solder_paste_margin 0)
		)
		(pad "4" smd roundrect
			(at 1.06621 0.95 270)
			(size 1.03828 0.53213)
			(layers "F.Cu" "F.Mask" "F.Paste")
			(roundrect_rratio 0.5)
			(net "+3.3V")
			(solder_mask_margin 0)
			(solder_paste_margin 0)
		)
		(pad "5" smd roundrect
			(at 1.06621 -0.95 270)
			(size 1.03828 0.53213)
			(layers "F.Cu" "F.Mask" "F.Paste")
			(roundrect_rratio 0.5)
			(net "EXT_EEPROM_WP")
			(solder_mask_margin 0)
			(solder_paste_margin 0)
		)
	)
	(footprint "Vault:CAPC1608X87X45ML20T05"
		(layer "F.Cu")
		(at 80.6261 125.8662 -90)
		(property "Reference" "C27"
			(at 2.7714 -0.026931 90)
			(unlocked yes)
			(layer "F.SilkS")
			(effects
				(font
					(size 0.762 0.762)
					(thickness 0.2286)
				)
			)
		)
		(property "Value" "0.1uF"
			(at 2.09443 2.657602 270)
			(unlocked yes)
			(layer "F.SilkS")
			(hide yes)
			(effects
				(font
					(size 1.524 1.524)
					(thickness 0.254)
				)
			)
		)
		(sheetname "USER_IO")
		(sheetfile "USER_IO.kicad_sch")
		(duplicate_pad_numbers_are_jumpers no)
		(pad "1" smd rect
			(at -0.7 0)
			(size 1.1 1.05)
			(layers "F.Cu" "F.Mask" "F.Paste")
			(net "+3.3V")
		)
		(pad "2" smd rect
			(at 0.7 0)
			(size 1.1 1.05)
			(layers "F.Cu" "F.Mask" "F.Paste")
			(net "GND")
		)
	)
	(footprint "Vault:CAPC1608X87X45ML20T05"
		(layer "F.Cu")
		(at 216.2675 116.3062 90)
		(property "Reference" "C15"
			(at 1.74 0.414345 90)
			(unlocked yes)
			(layer "F.SilkS")
			(effects
				(font
					(size 0.762 0.762)
					(thickness 0.2286)
				)
				(justify left bottom)
			)
		)
		(property "Value" "0.1uF"
			(at -6.58639 -5.5125 0)
			(unlocked yes)
			(layer "F.SilkS")
			(hide yes)
			(effects
				(font
					(size 1.524 1.524)
					(thickness 0.254)
				)
				(justify left bottom)
			)
		)
		(sheetname "POWER")
		(sheetfile "POWER.kicad_sch")
		(duplicate_pad_numbers_are_jumpers no)
		(pad "1" smd rect
			(at -0.7 0 180)
			(size 1.1 1.05)
			(layers "F.Cu" "F.Mask" "F.Paste")
			(net "GND")
		)
		(pad "2" smd rect
			(at 0.7 0 180)
			(size 1.1 1.05)
			(layers "F.Cu" "F.Mask" "F.Paste")
			(net "+5.0V")
		)
	)
	(footprint "Vault:RESC1608X55X25NL10T15"
		(layer "F.Cu")
		(at 125.4261 87.4162 180)
		(property "Reference" "R43"
			(at -0.5286 -1.326921 0)
			(unlocked yes)
			(layer "F.SilkS")
			(effects
				(font
					(size 0.762 0.762)
					(thickness 0.2286)
				)
			)
		)
		(property "Value" "DNI_49.9R"
			(at -2.911602 6.132045 90)
			(unlocked yes)
			(layer "F.SilkS")
			(hide yes)
			(effects
				(font
					(size 1.524 1.524)
					(thickness 0.254)
				)
			)
		)
		(sheetname "MAC")
		(sheetfile "MAC.kicad_sch")
		(duplicate_pad_numbers_are_jumpers no)
		(pad "1" smd rect
			(at -0.7 0 270)
			(size 0.9 0.7)
			(layers "F.Cu" "F.Mask" "F.Paste")
			(net "MAC_PPS_OUT")
		)
		(pad "2" smd rect
			(at 0.7 0 270)
			(size 0.9 0.7)
			(layers "F.Cu" "F.Mask" "F.Paste")
			(net "FPGA_MAC_PPS_OUT-")
		)
	)
)
